(kicad_pcb
	(version 20260206)
	(generator "pcbnew")
	(generator_version "10.0")
	(general
		(thickness 1.6)
		(legacy_teardrops no)
	)
	(paper "A4")
	(title_block
		(title "baseboard — 13948-1b.1110WZS1818.brd")
		(comment 1 "Honey Badger (Wiwynn) / footprint 1078 of 2523 (SU1), pads 348-464 of 672")
	)
	(layers
		(0 "F.Cu" signal "TOP")
		(4 "In1.Cu" signal "L2GND")
		(6 "In2.Cu" signal "L3")
		(8 "In3.Cu" signal "L4VCC")
		(10 "In4.Cu" signal "L5VCC")
		(12 "In5.Cu" signal "L6")
		(14 "In6.Cu" signal "L7GND")
		(2 "B.Cu" signal "BOTTOM")
		(9 "F.Adhes" user "F.Adhesive")
		(11 "B.Adhes" user "B.Adhesive")
		(13 "F.Paste" user "Package Geometry/Pastemask Top")
		(15 "B.Paste" user "Package Geometry/Pastemask Bottom")
		(5 "F.SilkS" user "Ref Des/Silkscreen Top")
		(7 "B.SilkS" user "Ref Des/Silkscreen Bottom")
		(1 "F.Mask" user "Board Geometry/Soldermask Top")
		(3 "B.Mask" user "Board Geometry/Soldermask Bottom")
		(17 "Dwgs.User" user "User.Drawings")
		(19 "Cmts.User" user "User.Comments")
		(21 "Eco1.User" user "User.Eco1")
		(23 "Eco2.User" user "User.Eco2")
		(25 "Edge.Cuts" user "Board Geometry/Outline")
		(27 "Margin" user)
		(31 "F.CrtYd" user "Package Geometry/Place Bound Top")
		(29 "B.CrtYd" user "Package Geometry/Place Bound Bottom")
		(35 "F.Fab" user "Ref Des/Assembly Top")
		(33 "B.Fab" user "Ref Des/Assembly Bottom")
	)
	(footprint ""
		(layer "F.Cu")
		(at 114.84991 -94.84995 90)
		(property "Reference" "SU1"
			(at 0 0 90)
			(layer "F.SilkS")
			(hide yes)
			(effects
				(font
					(size 1.27 1.27)
				)
			)
		)
		(property "Value" "SAS3X24RLC1-DB-500021106-GP"
			(at -21.4503 -7.4168 90)
			(unlocked yes)
			(layer "F.Fab")
			(hide yes)
			(effects
				(font
					(size 1.016 1.016)
					(thickness 0.1524)
				)
			)
		)
		(property "Device Type" "BGA672C27H83"
			(at -21.4503 -8.9408 90)
			(unlocked yes)
			(layer "F.Fab")
			(hide yes)
			(effects
				(font
					(size 1.016 1.016)
					(thickness 0.1524)
				)
			)
		)
		(duplicate_pad_numbers_are_jumpers no)
		(pad "H14" smd circle
			(at 0.500126 -5.500116 90)
			(size 0.4572 0.4572)
			(layers "F.Cu" "F.Mask" "F.Paste")
			(net "EXP_TACH_IN3")
		)
		(pad "H15" smd circle
			(at 1.500124 -5.500116 90)
			(size 0.4572 0.4572)
			(layers "F.Cu" "F.Mask" "F.Paste")
			(net "EXP_GPIO_4")
		)
		(pad "H16" smd circle
			(at 2.500122 -5.500116 90)
			(size 0.4572 0.4572)
			(layers "F.Cu" "F.Mask" "F.Paste")
			(net "P1V8_E")
		)
		(pad "H17" smd circle
			(at 3.50012 -5.500116 90)
			(size 0.4572 0.4572)
			(layers "F.Cu" "F.Mask" "F.Paste")
			(net "EXP_SIO_CLK_IN")
		)
		(pad "H18" smd circle
			(at 4.500118 -5.500116 90)
			(size 0.4572 0.4572)
			(layers "F.Cu" "F.Mask" "F.Paste")
			(net "EXP_I2C_SCL_2")
		)
		(pad "H19" smd circle
			(at 5.500116 -5.500116 90)
			(size 0.4572 0.4572)
			(layers "F.Cu" "F.Mask" "F.Paste")
			(net "GND")
		)
		(pad "H20" smd circle
			(at 6.500114 -5.500116 90)
			(size 0.4572 0.4572)
			(layers "F.Cu" "F.Mask" "F.Paste")
			(net "GND")
		)
		(pad "H21" smd circle
			(at 7.500112 -5.500116 90)
			(size 0.4572 0.4572)
			(layers "F.Cu" "F.Mask" "F.Paste")
			(net "SAS_GF_EXP_RX_DN13")
		)
		(pad "H22" smd circle
			(at 8.50011 -5.500116 90)
			(size 0.4572 0.4572)
			(layers "F.Cu" "F.Mask" "F.Paste")
			(net "SAS_GF_EXP_RX_DP13")
		)
		(pad "H23" smd circle
			(at 9.500108 -5.500116 90)
			(size 0.4572 0.4572)
			(layers "F.Cu" "F.Mask" "F.Paste")
			(net "GND")
		)
		(pad "H24" smd circle
			(at 10.500106 -5.500116 90)
			(size 0.4572 0.4572)
			(layers "F.Cu" "F.Mask" "F.Paste")
			(net "GB_VDDA")
		)
		(pad "H25" smd circle
			(at 11.500104 -5.500116 90)
			(size 0.4572 0.4572)
			(layers "F.Cu" "F.Mask" "F.Paste")
			(net "SAS_HDD_TX9_N")
		)
		(pad "H26" smd circle
			(at 12.500102 -5.500116 90)
			(size 0.4572 0.4572)
			(layers "F.Cu" "F.Mask" "F.Paste")
			(net "SAS_HDD_TX9_P")
		)
		(pad "J1" smd circle
			(at -12.500102 -4.500118 90)
			(size 0.4572 0.4572)
			(layers "F.Cu" "F.Mask" "F.Paste")
			(net "P1V8_E")
		)
		(pad "J2" smd circle
			(at -11.500104 -4.500118 90)
			(size 0.4572 0.4572)
			(layers "F.Cu" "F.Mask" "F.Paste")
			(net "SAS_HDD_LED11")
		)
		(pad "J3" smd circle
			(at -10.500106 -4.500118 90)
			(size 0.4572 0.4572)
			(layers "F.Cu" "F.Mask" "F.Paste")
			(net "EXP_ADC_IN0")
		)
		(pad "J4" smd circle
			(at -9.500108 -4.500118 90)
			(size 0.4572 0.4572)
			(layers "F.Cu" "F.Mask" "F.Paste")
			(net "TESTIBIAS")
		)
		(pad "J5" smd circle
			(at -8.50011 -4.500118 90)
			(size 0.4572 0.4572)
			(layers "F.Cu" "F.Mask" "F.Paste")
			(net "EXP_ADC_IN1")
		)
		(pad "J6" smd circle
			(at -7.500112 -4.500118 90)
			(size 0.4572 0.4572)
			(layers "F.Cu" "F.Mask" "F.Paste")
			(net "P1V8_E")
		)
		(pad "J7" smd circle
			(at -6.500114 -4.500118 90)
			(size 0.4572 0.4572)
			(layers "F.Cu" "F.Mask" "F.Paste")
			(net "GND")
		)
		(pad "J8" smd circle
			(at -5.500116 -4.500118 90)
			(size 0.4572 0.4572)
			(layers "F.Cu" "F.Mask" "F.Paste")
			(net "GND")
		)
		(pad "J9" smd circle
			(at -4.500118 -4.500118 90)
			(size 0.4572 0.4572)
			(layers "F.Cu" "F.Mask" "F.Paste")
			(net "Net_1129")
		)
		(pad "J10" smd circle
			(at -3.50012 -4.500118 90)
			(size 0.4572 0.4572)
			(layers "F.Cu" "F.Mask" "F.Paste")
			(net "GND")
		)
		(pad "J11" smd circle
			(at -2.500122 -4.500118 90)
			(size 0.4572 0.4572)
			(layers "F.Cu" "F.Mask" "F.Paste")
			(net "GND")
		)
		(pad "J12" smd circle
			(at -1.500124 -4.500118 90)
			(size 0.4572 0.4572)
			(layers "F.Cu" "F.Mask" "F.Paste")
			(net "GND")
		)
		(pad "J13" smd circle
			(at -0.500126 -4.500118 90)
			(size 0.4572 0.4572)
			(layers "F.Cu" "F.Mask" "F.Paste")
			(net "GND")
		)
		(pad "J14" smd circle
			(at 0.500126 -4.500118 90)
			(size 0.4572 0.4572)
			(layers "F.Cu" "F.Mask" "F.Paste")
			(net "GND")
		)
		(pad "J15" smd circle
			(at 1.500124 -4.500118 90)
			(size 0.4572 0.4572)
			(layers "F.Cu" "F.Mask" "F.Paste")
			(net "P1V8_E")
		)
		(pad "J16" smd circle
			(at 2.500122 -4.500118 90)
			(size 0.4572 0.4572)
			(layers "F.Cu" "F.Mask" "F.Paste")
			(net "GND")
		)
		(pad "J17" smd circle
			(at 3.50012 -4.500118 90)
			(size 0.4572 0.4572)
			(layers "F.Cu" "F.Mask" "F.Paste")
			(net "GND")
		)
		(pad "J18" smd circle
			(at 4.500118 -4.500118 90)
			(size 0.4572 0.4572)
			(layers "F.Cu" "F.Mask" "F.Paste")
			(net "GND")
		)
		(pad "J19" smd circle
			(at 5.500116 -4.500118 90)
			(size 0.4572 0.4572)
			(layers "F.Cu" "F.Mask" "F.Paste")
			(net "GND")
		)
		(pad "J20" smd circle
			(at 6.500114 -4.500118 90)
			(size 0.4572 0.4572)
			(layers "F.Cu" "F.Mask" "F.Paste")
			(net "GND")
		)
		(pad "J21" smd circle
			(at 7.500112 -4.500118 90)
			(size 0.4572 0.4572)
			(layers "F.Cu" "F.Mask" "F.Paste")
			(net "SAS_GF_EXP_RX_DN12")
		)
		(pad "J22" smd circle
			(at 8.50011 -4.500118 90)
			(size 0.4572 0.4572)
			(layers "F.Cu" "F.Mask" "F.Paste")
			(net "SAS_GF_EXP_RX_DP12")
		)
		(pad "J23" smd circle
			(at 9.500108 -4.500118 90)
			(size 0.4572 0.4572)
			(layers "F.Cu" "F.Mask" "F.Paste")
			(net "GB_VDDA")
		)
		(pad "J24" smd circle
			(at 10.500106 -4.500118 90)
			(size 0.4572 0.4572)
			(layers "F.Cu" "F.Mask" "F.Paste")
			(net "SAS_HDD_TX8_N")
		)
		(pad "J25" smd circle
			(at 11.500104 -4.500118 90)
			(size 0.4572 0.4572)
			(layers "F.Cu" "F.Mask" "F.Paste")
			(net "SAS_HDD_TX8_P")
		)
		(pad "J26" smd circle
			(at 12.500102 -4.500118 90)
			(size 0.4572 0.4572)
			(layers "F.Cu" "F.Mask" "F.Paste")
			(net "GND")
		)
		(pad "K1" smd circle
			(at -12.500102 -3.50012 90)
			(size 0.4572 0.4572)
			(layers "F.Cu" "F.Mask" "F.Paste")
			(net "EXP_LED_15")
		)
		(pad "K2" smd circle
			(at -11.500104 -3.50012 90)
			(size 0.4572 0.4572)
			(layers "F.Cu" "F.Mask" "F.Paste")
			(net "EXP_LED_12")
		)
		(pad "K3" smd circle
			(at -10.500106 -3.50012 90)
			(size 0.4572 0.4572)
			(layers "F.Cu" "F.Mask" "F.Paste")
			(net "GND")
		)
		(pad "K4" smd circle
			(at -9.500108 -3.50012 90)
			(size 0.4572 0.4572)
			(layers "F.Cu" "F.Mask" "F.Paste")
			(net "EXP_LED_13")
		)
		(pad "K5" smd circle
			(at -8.50011 -3.50012 90)
			(size 0.4572 0.4572)
			(layers "F.Cu" "F.Mask" "F.Paste")
			(net "GND")
		)
		(pad "K6" smd circle
			(at -7.500112 -3.50012 90)
			(size 0.4572 0.4572)
			(layers "F.Cu" "F.Mask" "F.Paste")
			(net "P1V8_E")
		)
		(pad "K7" smd circle
			(at -6.500114 -3.50012 90)
			(size 0.4572 0.4572)
			(layers "F.Cu" "F.Mask" "F.Paste")
			(net "GND")
		)
		(pad "K8" smd circle
			(at -5.500116 -3.50012 90)
			(size 0.4572 0.4572)
			(layers "F.Cu" "F.Mask" "F.Paste")
			(net "GND")
		)
		(pad "K9" smd circle
			(at -4.500118 -3.50012 90)
			(size 0.4572 0.4572)
			(layers "F.Cu" "F.Mask" "F.Paste")
			(net "P0V9_E")
		)
		(pad "K10" smd circle
			(at -3.50012 -3.50012 90)
			(size 0.4572 0.4572)
			(layers "F.Cu" "F.Mask" "F.Paste")
			(net "GND")
		)
		(pad "K11" smd circle
			(at -2.500122 -3.50012 90)
			(size 0.4572 0.4572)
			(layers "F.Cu" "F.Mask" "F.Paste")
			(net "P0V9_E")
		)
		(pad "K12" smd circle
			(at -1.500124 -3.50012 90)
			(size 0.4572 0.4572)
			(layers "F.Cu" "F.Mask" "F.Paste")
			(net "GND")
		)
		(pad "K13" smd circle
			(at -0.500126 -3.50012 90)
			(size 0.4572 0.4572)
			(layers "F.Cu" "F.Mask" "F.Paste")
			(net "P0V9_E")
		)
		(pad "K14" smd circle
			(at 0.500126 -3.50012 90)
			(size 0.4572 0.4572)
			(layers "F.Cu" "F.Mask" "F.Paste")
			(net "GND")
		)
		(pad "K15" smd circle
			(at 1.500124 -3.50012 90)
			(size 0.4572 0.4572)
			(layers "F.Cu" "F.Mask" "F.Paste")
			(net "P0V9_E")
		)
		(pad "K16" smd circle
			(at 2.500122 -3.50012 90)
			(size 0.4572 0.4572)
			(layers "F.Cu" "F.Mask" "F.Paste")
			(net "GND")
		)
		(pad "K17" smd circle
			(at 3.50012 -3.50012 90)
			(size 0.4572 0.4572)
			(layers "F.Cu" "F.Mask" "F.Paste")
			(net "P0V9_E")
		)
		(pad "K18" smd circle
			(at 4.500118 -3.50012 90)
			(size 0.4572 0.4572)
			(layers "F.Cu" "F.Mask" "F.Paste")
			(net "GND")
		)
		(pad "K19" smd circle
			(at 5.500116 -3.50012 90)
			(size 0.4572 0.4572)
			(layers "F.Cu" "F.Mask" "F.Paste")
			(net "GB_VDDH2")
		)
		(pad "K20" smd circle
			(at 6.500114 -3.50012 90)
			(size 0.4572 0.4572)
			(layers "F.Cu" "F.Mask" "F.Paste")
			(net "GB_VDDA")
		)
		(pad "K21" smd circle
			(at 7.500112 -3.50012 90)
			(size 0.4572 0.4572)
			(layers "F.Cu" "F.Mask" "F.Paste")
			(net "SAS_GF_EXP_RX_DN11")
		)
		(pad "K22" smd circle
			(at 8.50011 -3.50012 90)
			(size 0.4572 0.4572)
			(layers "F.Cu" "F.Mask" "F.Paste")
			(net "SAS_GF_EXP_RX_DP11")
		)
		(pad "K23" smd circle
			(at 9.500108 -3.50012 90)
			(size 0.4572 0.4572)
			(layers "F.Cu" "F.Mask" "F.Paste")
			(net "GND")
		)
		(pad "K24" smd circle
			(at 10.500106 -3.50012 90)
			(size 0.4572 0.4572)
			(layers "F.Cu" "F.Mask" "F.Paste")
			(net "GB_VDDA")
		)
		(pad "K25" smd circle
			(at 11.500104 -3.50012 90)
			(size 0.4572 0.4572)
			(layers "F.Cu" "F.Mask" "F.Paste")
			(net "SAS_HDD_TX7_N")
		)
		(pad "K26" smd circle
			(at 12.500102 -3.50012 90)
			(size 0.4572 0.4572)
			(layers "F.Cu" "F.Mask" "F.Paste")
			(net "SAS_HDD_TX7_P")
		)
		(pad "L1" smd circle
			(at -12.500102 -2.500122 90)
			(size 0.4572 0.4572)
			(layers "F.Cu" "F.Mask" "F.Paste")
			(net "SAS_HDD_LED23")
		)
		(pad "L2" smd circle
			(at -11.500104 -2.500122 90)
			(size 0.4572 0.4572)
			(layers "F.Cu" "F.Mask" "F.Paste")
			(net "SAS_STATUS_LED17")
		)
		(pad "L3" smd circle
			(at -10.500106 -2.500122 90)
			(size 0.4572 0.4572)
			(layers "F.Cu" "F.Mask" "F.Paste")
			(net "P1V8_E")
		)
		(pad "L4" smd circle
			(at -9.500108 -2.500122 90)
			(size 0.4572 0.4572)
			(layers "F.Cu" "F.Mask" "F.Paste")
			(net "EXP_LED18")
		)
		(pad "L5" smd circle
			(at -8.50011 -2.500122 90)
			(size 0.4572 0.4572)
			(layers "F.Cu" "F.Mask" "F.Paste")
			(net "EXP_LED_14")
		)
		(pad "L6" smd circle
			(at -7.500112 -2.500122 90)
			(size 0.4572 0.4572)
			(layers "F.Cu" "F.Mask" "F.Paste")
			(net "GND")
		)
		(pad "L7" smd circle
			(at -6.500114 -2.500122 90)
			(size 0.4572 0.4572)
			(layers "F.Cu" "F.Mask" "F.Paste")
			(net "SYSPLL_VDDA09")
		)
		(pad "L8" smd circle
			(at -5.500116 -2.500122 90)
			(size 0.4572 0.4572)
			(layers "F.Cu" "F.Mask" "F.Paste")
			(net "GND")
		)
		(pad "L9" smd circle
			(at -4.500118 -2.500122 90)
			(size 0.4572 0.4572)
			(layers "F.Cu" "F.Mask" "F.Paste")
			(net "GND")
		)
		(pad "L10" smd circle
			(at -3.50012 -2.500122 90)
			(size 0.4572 0.4572)
			(layers "F.Cu" "F.Mask" "F.Paste")
			(net "P0V9_E")
		)
		(pad "L11" smd circle
			(at -2.500122 -2.500122 90)
			(size 0.4572 0.4572)
			(layers "F.Cu" "F.Mask" "F.Paste")
			(net "GND")
		)
		(pad "L12" smd circle
			(at -1.500124 -2.500122 90)
			(size 0.4572 0.4572)
			(layers "F.Cu" "F.Mask" "F.Paste")
			(net "P0V9_E")
		)
		(pad "L13" smd circle
			(at -0.500126 -2.500122 90)
			(size 0.4572 0.4572)
			(layers "F.Cu" "F.Mask" "F.Paste")
			(net "GND")
		)
		(pad "L14" smd circle
			(at 0.500126 -2.500122 90)
			(size 0.4572 0.4572)
			(layers "F.Cu" "F.Mask" "F.Paste")
			(net "P0V9_E")
		)
		(pad "L15" smd circle
			(at 1.500124 -2.500122 90)
			(size 0.4572 0.4572)
			(layers "F.Cu" "F.Mask" "F.Paste")
			(net "GND")
		)
		(pad "L16" smd circle
			(at 2.500122 -2.500122 90)
			(size 0.4572 0.4572)
			(layers "F.Cu" "F.Mask" "F.Paste")
			(net "P0V9_E")
		)
		(pad "L17" smd circle
			(at 3.50012 -2.500122 90)
			(size 0.4572 0.4572)
			(layers "F.Cu" "F.Mask" "F.Paste")
			(net "GND")
		)
		(pad "L18" smd circle
			(at 4.500118 -2.500122 90)
			(size 0.4572 0.4572)
			(layers "F.Cu" "F.Mask" "F.Paste")
			(net "GND")
		)
		(pad "L19" smd circle
			(at 5.500116 -2.500122 90)
			(size 0.4572 0.4572)
			(layers "F.Cu" "F.Mask" "F.Paste")
			(net "GB_VDDH2")
		)
		(pad "L20" smd circle
			(at 6.500114 -2.500122 90)
			(size 0.4572 0.4572)
			(layers "F.Cu" "F.Mask" "F.Paste")
			(net "GND")
		)
		(pad "L21" smd circle
			(at 7.500112 -2.500122 90)
			(size 0.4572 0.4572)
			(layers "F.Cu" "F.Mask" "F.Paste")
			(net "SAS_GF_EXP_RX_DN10")
		)
		(pad "L22" smd circle
			(at 8.50011 -2.500122 90)
			(size 0.4572 0.4572)
			(layers "F.Cu" "F.Mask" "F.Paste")
			(net "SAS_GF_EXP_RX_DP10")
		)
		(pad "L23" smd circle
			(at 9.500108 -2.500122 90)
			(size 0.4572 0.4572)
			(layers "F.Cu" "F.Mask" "F.Paste")
			(net "GB_VDDA")
		)
		(pad "L24" smd circle
			(at 10.500106 -2.500122 90)
			(size 0.4572 0.4572)
			(layers "F.Cu" "F.Mask" "F.Paste")
			(net "SAS_HDD_TX6_N")
		)
		(pad "L25" smd circle
			(at 11.500104 -2.500122 90)
			(size 0.4572 0.4572)
			(layers "F.Cu" "F.Mask" "F.Paste")
			(net "SAS_HDD_TX6_P")
		)
		(pad "L26" smd circle
			(at 12.500102 -2.500122 90)
			(size 0.4572 0.4572)
			(layers "F.Cu" "F.Mask" "F.Paste")
			(net "GND")
		)
		(pad "M1" smd circle
			(at -12.500102 -1.500124 90)
			(size 0.4572 0.4572)
			(layers "F.Cu" "F.Mask" "F.Paste")
			(net "EXP_TEST_MUX28")
		)
		(pad "M2" smd circle
			(at -11.500104 -1.500124 90)
			(size 0.4572 0.4572)
			(layers "F.Cu" "F.Mask" "F.Paste")
			(net "EXP_TEST_MUX25")
		)
		(pad "M3" smd circle
			(at -10.500106 -1.500124 90)
			(size 0.4572 0.4572)
			(layers "F.Cu" "F.Mask" "F.Paste")
			(net "GND")
		)
		(pad "M4" smd circle
			(at -9.500108 -1.500124 90)
			(size 0.4572 0.4572)
			(layers "F.Cu" "F.Mask" "F.Paste")
			(net "SAS_HDD_LED20")
		)
		(pad "M5" smd circle
			(at -8.50011 -1.500124 90)
			(size 0.4572 0.4572)
			(layers "F.Cu" "F.Mask" "F.Paste")
			(net "EXP_LED19")
		)
		(pad "M6" smd circle
			(at -7.500112 -1.500124 90)
			(size 0.4572 0.4572)
			(layers "F.Cu" "F.Mask" "F.Paste")
			(net "P1V8_E")
		)
		(pad "M7" smd circle
			(at -6.500114 -1.500124 90)
			(size 0.4572 0.4572)
			(layers "F.Cu" "F.Mask" "F.Paste")
			(net "SYSPLL_VDDA18")
		)
		(pad "M8" smd circle
			(at -5.500116 -1.500124 90)
			(size 0.4572 0.4572)
			(layers "F.Cu" "F.Mask" "F.Paste")
			(net "GND")
		)
		(pad "M9" smd circle
			(at -4.500118 -1.500124 90)
			(size 0.4572 0.4572)
			(layers "F.Cu" "F.Mask" "F.Paste")
			(net "P0V9_E")
		)
		(pad "M10" smd circle
			(at -3.50012 -1.500124 90)
			(size 0.4572 0.4572)
			(layers "F.Cu" "F.Mask" "F.Paste")
			(net "GND")
		)
		(pad "M11" smd circle
			(at -2.500122 -1.500124 90)
			(size 0.4572 0.4572)
			(layers "F.Cu" "F.Mask" "F.Paste")
			(net "P0V9_E")
		)
		(pad "M12" smd circle
			(at -1.500124 -1.500124 90)
			(size 0.4572 0.4572)
			(layers "F.Cu" "F.Mask" "F.Paste")
			(net "GND")
		)
		(pad "M13" smd circle
			(at -0.500126 -1.500124 90)
			(size 0.4572 0.4572)
			(layers "F.Cu" "F.Mask" "F.Paste")
			(net "P0V9_E")
		)
		(pad "M14" smd circle
			(at 0.500126 -1.500124 90)
			(size 0.4572 0.4572)
			(layers "F.Cu" "F.Mask" "F.Paste")
			(net "GND")
		)
		(pad "M15" smd circle
			(at 1.500124 -1.500124 90)
			(size 0.4572 0.4572)
			(layers "F.Cu" "F.Mask" "F.Paste")
			(net "P0V9_E")
		)
		(pad "M16" smd circle
			(at 2.500122 -1.500124 90)
			(size 0.4572 0.4572)
			(layers "F.Cu" "F.Mask" "F.Paste")
			(net "GND")
		)
		(pad "M17" smd circle
			(at 3.50012 -1.500124 90)
			(size 0.4572 0.4572)
			(layers "F.Cu" "F.Mask" "F.Paste")
			(net "P0V9_E")
		)
		(pad "M18" smd circle
			(at 4.500118 -1.500124 90)
			(size 0.4572 0.4572)
			(layers "F.Cu" "F.Mask" "F.Paste")
			(net "GND")
		)
		(pad "M19" smd circle
			(at 5.500116 -1.500124 90)
			(size 0.4572 0.4572)
			(layers "F.Cu" "F.Mask" "F.Paste")
			(net "GB_VDDH2")
		)
		(pad "M20" smd circle
			(at 6.500114 -1.500124 90)
			(size 0.4572 0.4572)
			(layers "F.Cu" "F.Mask" "F.Paste")
			(net "GB_VDDA")
		)
		(pad "M21" smd circle
			(at 7.500112 -1.500124 90)
			(size 0.4572 0.4572)
			(layers "F.Cu" "F.Mask" "F.Paste")
			(net "SAS_GF_EXP_RX_DN9")
		)
		(pad "M22" smd circle
			(at 8.50011 -1.500124 90)
			(size 0.4572 0.4572)
			(layers "F.Cu" "F.Mask" "F.Paste")
			(net "SAS_GF_EXP_RX_DP9")
		)
		(pad "M23" smd circle
			(at 9.500108 -1.500124 90)
			(size 0.4572 0.4572)
			(layers "F.Cu" "F.Mask" "F.Paste")
			(net "GND")
		)
		(pad "M24" smd circle
			(at 10.500106 -1.500124 90)
			(size 0.4572 0.4572)
			(layers "F.Cu" "F.Mask" "F.Paste")
			(net "GB_VDDA")
		)
		(pad "M25" smd circle
			(at 11.500104 -1.500124 90)
			(size 0.4572 0.4572)
			(layers "F.Cu" "F.Mask" "F.Paste")
			(net "SAS_HDD_TX5_N")
		)
		(pad "M26" smd circle
			(at 12.500102 -1.500124 90)
			(size 0.4572 0.4572)
			(layers "F.Cu" "F.Mask" "F.Paste")
			(net "SAS_HDD_TX5_P")
		)
	)
)
